# TIMECARD (Time Appliance Project (Time Card)) — schematic netlist excerpt (pin names and nets, part order shuffled) for the footprints in the layout excerpt that follows; sources: Cadence DE-HDL packaged netlist, KiCad conversion of R4006-B0001-02_R01.brd

R391  RESISTOR  33OHM 1%  pkg SMC_0402R_H016  page 26 : \1\ = SMA3_LED_BLUE_N ; \2\ = UNNAMED_14_LED4PV14_I267_1
TP20  TP_PIONT  pkg TP010CT020B030_PTH  page 25 : \1\ = SEC_EEPROM_WP

(kicad_pcb
	(version 20260206)
	(generator "pcbnew")
	(generator_version "10.0")
	(general
		(thickness 1.6)
		(legacy_teardrops no)
	)
	(paper "A4")
	(title_block
		(title "timecard-production-celestica-r4006 — R4006-B0001-02_R01.brd")
		(comment 1 "Time Appliance Project (Time Card) / footprints 194-196 of 1113")
	)
	(layers
		(0 "F.Cu" signal "TOP")
		(4 "In1.Cu" signal "L02_GND1")
		(6 "In2.Cu" signal "L03_SIG1")
		(8 "In3.Cu" signal "L04_GND2")
		(10 "In4.Cu" signal "L05_VCC1")
		(12 "In5.Cu" signal "L06_VCC2")
		(14 "In6.Cu" signal "L07_GND3")
		(16 "In7.Cu" signal "L08_SIG2")
		(18 "In8.Cu" signal "L09_GND4")
		(2 "B.Cu" signal "BOTTOM")
		(9 "F.Adhes" user "F.Adhesive")
		(11 "B.Adhes" user "B.Adhesive")
		(13 "F.Paste" user "Package Geometry/Pastemask Top")
		(15 "B.Paste" user "Package Geometry/Pastemask Bottom")
		(5 "F.SilkS" user "Ref Des/Silkscreen Top")
		(7 "B.SilkS" user "Ref Des/Silkscreen Bottom")
		(1 "F.Mask" user "Board Geometry/Soldermask Top")
		(3 "B.Mask" user "Board Geometry/Soldermask Bottom")
		(17 "Dwgs.User" user "User.Drawings")
		(19 "Cmts.User" user "User.Comments")
		(21 "Eco1.User" user "User.Eco1")
		(23 "Eco2.User" user "User.Eco2")
		(25 "Edge.Cuts" user "Board Geometry/Outline")
		(27 "Margin" user)
		(31 "F.CrtYd" user "Package Geometry/Place Bound Top")
		(29 "B.CrtYd" user "Package Geometry/Place Bound Bottom")
		(35 "F.Fab" user "Ref Des/Assembly Top")
		(33 "B.Fab" user "Ref Des/Assembly Bottom")
	)
	(footprint ""
		(layer "F.Cu")
		(at 5.0038 -68.201032 90)
		(property "Reference" "R391"
			(at 3.553968 -0.51943 90)
			(unlocked yes)
			(layer "F.SilkS")
			(effects
				(font
					(size 0.7874 0.5842)
					(thickness 0.1524)
				)
			)
		)
		(property "Value" "VAL*"
			(at 0.02032 2.13233 90)
			(unlocked yes)
			(layer "F.Fab")
			(hide yes)
			(effects
				(font
					(size 0.7874 0.5842)
					(thickness 0.1524)
				)
			)
		)
		(property "Tolerance" "TOL*"
			(at 0.044704 3.05435 90)
			(unlocked yes)
			(layer "Cmts.User")
			(hide yes)
			(effects
				(font
					(size 0.7874 0.5842)
					(thickness 0.1524)
				)
			)
		)
		(property "User Part Number" "PARTNUM*"
			(at 0.02032 4.024884 90)
			(unlocked yes)
			(layer "Cmts.User")
			(hide yes)
			(effects
				(font
					(size 0.7874 0.5842)
					(thickness 0.1524)
				)
			)
		)
		(property "Device Type" "RESISTOR-G155-133R0-01,33OHM,1%"
			(at 0.008382 1.210564 90)
			(unlocked yes)
			(layer "F.Fab")
			(hide yes)
			(effects
				(font
					(size 0.7874 0.5842)
					(thickness 0.1524)
				)
			)
		)
		(duplicate_pad_numbers_are_jumpers no)
		(fp_line
			(start 1.143 -0.5588)
			(end -1.143 -0.5588)
			(stroke
				(width 0.1)
				(type default)
			)
			(layer "F.SilkS")
		)
		(fp_line
			(start -1.143 -0.5588)
			(end -1.143 0.5588)
			(stroke
				(width 0.1)
				(type default)
			)
			(layer "F.SilkS")
		)
		(fp_line
			(start 1.143 0.5588)
			(end 1.143 -0.5588)
			(stroke
				(width 0.1)
				(type default)
			)
			(layer "F.SilkS")
		)
		(fp_line
			(start -1.143 0.5588)
			(end 1.143 0.5588)
			(stroke
				(width 0.1)
				(type default)
			)
			(layer "F.SilkS")
		)
		(fp_rect
			(start -1.143 -0.5588)
			(end 1.143 0.5588)
			(stroke
				(width 0)
				(type default)
			)
			(fill no)
			(layer "F.CrtYd")
		)
		(fp_line
			(start 0.508 -0.3048)
			(end -0.508 -0.3048)
			(stroke
				(width 0.1)
				(type default)
			)
			(layer "F.Fab")
		)
		(fp_line
			(start -0.508 -0.3048)
			(end -0.508 0.3048)
			(stroke
				(width 0.1)
				(type default)
			)
			(layer "F.Fab")
		)
		(fp_line
			(start 0.508 0.3048)
			(end 0.508 -0.3048)
			(stroke
				(width 0.1)
				(type default)
			)
			(layer "F.Fab")
		)
		(fp_line
			(start -0.508 0.3048)
			(end 0.508 0.3048)
			(stroke
				(width 0.1)
				(type default)
			)
			(layer "F.Fab")
		)
		(pad "1" smd rect
			(at -0.5334 0 90)
			(size 0.7112 0.6096)
			(layers "F.Cu" "F.Mask" "F.Paste")
			(net "SMA3_LED_BLUE_N")
		)
		(pad "2" smd rect
			(at 0.5334 0 90)
			(size 0.7112 0.6096)
			(layers "F.Cu" "F.Mask" "F.Paste")
			(net "UNNAMED_14_LED4PV14_I267_1")
		)
		(zone
			(layer "F.Cu")
			(hatch none 0.5)
			(connect_pads
				(clearance 0)
			)
			(min_thickness 0.25)
			(keepout
				(tracks not_allowed)
				(vias allowed)
				(pads allowed)
				(copperpour not_allowed)
				(footprints allowed)
			)
			(placement
				(enabled no)
				(sheetname "")
			)
			(fill
				(thermal_gap 0.5)
				(thermal_bridge_width 0.5)
				(island_removal_mode 0)
			)
			(polygon
				(pts
					(xy 4.699 -68.124832) (xy 5.3086 -68.124832) (xy 5.3086 -68.277232) (xy 4.699 -68.277232)
				)
			)
		)
		(zone
			(layer "F.Cu")
			(hatch none 0.5)
			(connect_pads
				(clearance 0)
			)
			(min_thickness 0.25)
			(keepout
				(tracks allowed)
				(vias not_allowed)
				(pads allowed)
				(copperpour not_allowed)
				(footprints allowed)
			)
			(placement
				(enabled no)
				(sheetname "")
			)
			(fill
				(thermal_gap 0.5)
				(thermal_bridge_width 0.5)
				(island_removal_mode 0)
			)
			(polygon
				(pts
					(xy 4.699 -68.124832) (xy 5.3086 -68.124832) (xy 5.3086 -68.277232) (xy 4.699 -68.277232)
				)
			)
		)
	)
	(footprint ""
		(layer "F.Cu")
		(at 50.419 -131.953)
		(property "Reference" "SP72"
			(at 0 0 0)
			(layer "F.SilkS")
			(hide yes)
			(effects
				(font
					(size 1.27 1.27)
				)
			)
		)
		(property "Value" ""
			(at 0 0 0)
			(layer "F.Fab")
			(effects
				(font
					(size 1.27 1.27)
				)
			)
		)
		(duplicate_pad_numbers_are_jumpers no)
	)
	(footprint ""
		(layer "F.Cu")
		(at 19.177 -15.748)
		(property "Reference" "TP20"
			(at 0.9398 0.86995 0)
			(unlocked yes)
			(layer "F.SilkS")
			(effects
				(font
					(size 0.635 0.4064)
					(thickness 0.1524)
				)
				(justify left)
			)
		)
		(property "Value" ""
			(at 0 0 0)
			(layer "F.Fab")
			(effects
				(font
					(size 1.27 1.27)
				)
			)
		)
		(property "Device Type" "TP_PIONT-TP010CT020B030_PTH-TPA"
			(at -1.341882 0.996696 0)
			(unlocked yes)
			(layer "F.Fab")
			(hide yes)
			(effects
				(font
					(size 0.7874 0.5842)
					(thickness 0.000001)
				)
				(justify left)
			)
		)
		(duplicate_pad_numbers_are_jumpers no)
		(fp_poly
			(pts
				(arc
					(start 0.889 0)
					(mid -0.889 0)
					(end 0.889 0)
				)
			)
			(stroke
				(width 0)
				(type default)
			)
			(fill no)
			(layer "B.CrtYd")
		)
		(fp_poly
			(pts
				(arc
					(start 0.889 0)
					(mid -0.889 0)
					(end 0.889 0)
				)
			)
			(stroke
				(width 0)
				(type default)
			)
			(fill no)
			(layer "F.CrtYd")
		)
		(pad "1" thru_hole circle
			(at 0 0)
			(size 0.508 0.508)
			(drill 0.254)
			(layers "*.Cu" "*.Mask")
			(remove_unused_layers no)
			(net "SEC_EEPROM_WP")
			(clearance 0.1016)
			(padstack
				(mode front_inner_back)
				(layer "Inner"
					(shape circle)
					(size 0.508 0.508)
					(clearance 0.1016)
				)
				(layer "B.Cu"
					(shape circle)
					(size 0.762 0.762)
					(clearance -0.0254)
				)
			)
		)
	)
)
